(kicad_pcb
	(version 20260206)
	(generator "pcbnew")
	(generator_version "10.0")
	(general
		(thickness 1.6)
		(legacy_teardrops no)
	)
	(paper "A4")
	(title_block
		(title "04192023_DAF0TMB3IC0_F0TG_MB_C_brd_V02_OCP.brd")
		(comment 1 "Grand Teton / footprints 1965-1970 of 8354")
	)
	(layers
		(0 "F.Cu" signal "TOP")
		(4 "In1.Cu" signal "GND")
		(6 "In2.Cu" signal "IN1")
		(8 "In3.Cu" signal "GND1")
		(10 "In4.Cu" signal "IN2")
		(12 "In5.Cu" signal "GND2")
		(14 "In6.Cu" signal "IN3")
		(16 "In7.Cu" signal "GND3")
		(18 "In8.Cu" signal "VCC")
		(20 "In9.Cu" signal "VCC1")
		(22 "In10.Cu" signal "GND4")
		(24 "In11.Cu" signal "IN4")
		(26 "In12.Cu" signal "GND5")
		(28 "In13.Cu" signal "IN5")
		(30 "In14.Cu" signal "GND6")
		(32 "In15.Cu" signal "IN6")
		(34 "In16.Cu" signal "GND7")
		(2 "B.Cu" signal "BOTTOM")
		(9 "F.Adhes" user "F.Adhesive")
		(11 "B.Adhes" user "B.Adhesive")
		(13 "F.Paste" user "Package Geometry/Pastemask Top")
		(15 "B.Paste" user "Package Geometry/Pastemask Bottom")
		(5 "F.SilkS" user "Ref Des/Silkscreen Top")
		(7 "B.SilkS" user "Ref Des/Silkscreen Bottom")
		(1 "F.Mask" user "Board Geometry/Soldermask Top")
		(3 "B.Mask" user "Board Geometry/Soldermask Bottom")
		(17 "Dwgs.User" user "User.Drawings")
		(19 "Cmts.User" user "User.Comments")
		(21 "Eco1.User" user "User.Eco1")
		(23 "Eco2.User" user "User.Eco2")
		(25 "Edge.Cuts" user "Board Geometry/Outline")
		(27 "Margin" user)
		(31 "F.CrtYd" user "Package Geometry/Place Bound Top")
		(29 "B.CrtYd" user "Package Geometry/Place Bound Bottom")
		(35 "F.Fab" user "Ref Des/Assembly Top")
		(33 "B.Fab" user "Ref Des/Assembly Bottom")
	)
	(footprint ""
		(layer "F.Cu")
		(at 120.358662 -15.247366)
		(property "Reference" "R4193"
			(at 0 0 0)
			(layer "F.SilkS")
			(hide yes)
			(effects
				(font
					(size 1.27 1.27)
				)
			)
		)
		(property "Value" ""
			(at 0 0 0)
			(layer "F.Fab")
			(effects
				(font
					(size 1.27 1.27)
				)
			)
		)
		(duplicate_pad_numbers_are_jumpers no)
		(fp_line
			(start -0.7874 -0.4064)
			(end 0.7874 -0.4064)
			(stroke
				(width 0.1524)
				(type default)
			)
			(layer "F.SilkS")
		)
		(fp_line
			(start -0.7874 0.4064)
			(end -0.7874 -0.4064)
			(stroke
				(width 0.1524)
				(type default)
			)
			(layer "F.SilkS")
		)
		(fp_line
			(start 0.7874 -0.4064)
			(end 0.7874 0.4064)
			(stroke
				(width 0.1524)
				(type default)
			)
			(layer "F.SilkS")
		)
		(fp_line
			(start 0.7874 0.4064)
			(end -0.7874 0.4064)
			(stroke
				(width 0.1524)
				(type default)
			)
			(layer "F.SilkS")
		)
		(fp_line
			(start -0.67945 -0.305054)
			(end -0.12065 -0.305054)
			(stroke
				(width 0.1)
				(type default)
			)
			(layer "F.Fab")
		)
		(fp_line
			(start -0.67945 0.3048)
			(end -0.67945 -0.305054)
			(stroke
				(width 0.1)
				(type default)
			)
			(layer "F.Fab")
		)
		(fp_line
			(start -0.12065 -0.305054)
			(end -0.12065 -0.2794)
			(stroke
				(width 0.1)
				(type default)
			)
			(layer "F.Fab")
		)
		(fp_line
			(start -0.12065 -0.2794)
			(end 0.12065 -0.2794)
			(stroke
				(width 0.1)
				(type default)
			)
			(layer "F.Fab")
		)
		(fp_line
			(start -0.12065 0.2794)
			(end -0.12065 0.3048)
			(stroke
				(width 0.1)
				(type default)
			)
			(layer "F.Fab")
		)
		(fp_line
			(start -0.12065 0.3048)
			(end -0.67945 0.3048)
			(stroke
				(width 0.1)
				(type default)
			)
			(layer "F.Fab")
		)
		(fp_line
			(start 0.120396 0.2794)
			(end -0.12065 0.2794)
			(stroke
				(width 0.1)
				(type default)
			)
			(layer "F.Fab")
		)
		(fp_line
			(start 0.120396 0.3048)
			(end 0.120396 0.2794)
			(stroke
				(width 0.1)
				(type default)
			)
			(layer "F.Fab")
		)
		(fp_line
			(start 0.12065 -0.3048)
			(end 0.67945 -0.3048)
			(stroke
				(width 0.1)
				(type default)
			)
			(layer "F.Fab")
		)
		(fp_line
			(start 0.12065 -0.2794)
			(end 0.12065 -0.3048)
			(stroke
				(width 0.1)
				(type default)
			)
			(layer "F.Fab")
		)
		(fp_line
			(start 0.67945 -0.3048)
			(end 0.67945 0.3048)
			(stroke
				(width 0.1)
				(type default)
			)
			(layer "F.Fab")
		)
		(fp_line
			(start 0.67945 0.3048)
			(end 0.120396 0.3048)
			(stroke
				(width 0.1)
				(type default)
			)
			(layer "F.Fab")
		)
		(pad "1" smd circle
			(at -0.40005 0)
			(size 0 0)
			(layers "F.Cu" "F.Mask" "F.Paste")
			(net "U273_3_ADD1")
		)
		(pad "2" smd circle
			(at 0.40005 0)
			(size 0 0)
			(layers "F.Cu" "F.Mask" "F.Paste")
			(net "GND")
		)
	)
	(footprint ""
		(layer "F.Cu")
		(at 19.915124 -407.976578 -90)
		(property "Reference" "R6787"
			(at 0 0 270)
			(layer "F.SilkS")
			(hide yes)
			(effects
				(font
					(size 1.27 1.27)
				)
			)
		)
		(property "Value" ""
			(at 0 0 270)
			(layer "F.Fab")
			(effects
				(font
					(size 1.27 1.27)
				)
			)
		)
		(duplicate_pad_numbers_are_jumpers no)
		(fp_line
			(start -0.7874 0.4064)
			(end -0.7874 -0.4064)
			(stroke
				(width 0.1524)
				(type default)
			)
			(layer "F.SilkS")
		)
		(fp_line
			(start 0.7874 0.4064)
			(end -0.7874 0.4064)
			(stroke
				(width 0.1524)
				(type default)
			)
			(layer "F.SilkS")
		)
		(fp_line
			(start -0.7874 -0.4064)
			(end 0.7874 -0.4064)
			(stroke
				(width 0.1524)
				(type default)
			)
			(layer "F.SilkS")
		)
		(fp_line
			(start 0.7874 -0.4064)
			(end 0.7874 0.4064)
			(stroke
				(width 0.1524)
				(type default)
			)
			(layer "F.SilkS")
		)
		(fp_line
			(start -0.67945 0.3048)
			(end -0.67945 -0.305054)
			(stroke
				(width 0.1)
				(type default)
			)
			(layer "F.Fab")
		)
		(fp_line
			(start -0.12065 0.3048)
			(end -0.67945 0.3048)
			(stroke
				(width 0.1)
				(type default)
			)
			(layer "F.Fab")
		)
		(fp_line
			(start 0.120396 0.3048)
			(end 0.120396 0.2794)
			(stroke
				(width 0.1)
				(type default)
			)
			(layer "F.Fab")
		)
		(fp_line
			(start 0.67945 0.3048)
			(end 0.120396 0.3048)
			(stroke
				(width 0.1)
				(type default)
			)
			(layer "F.Fab")
		)
		(fp_line
			(start -0.12065 0.2794)
			(end -0.12065 0.3048)
			(stroke
				(width 0.1)
				(type default)
			)
			(layer "F.Fab")
		)
		(fp_line
			(start 0.120396 0.2794)
			(end -0.12065 0.2794)
			(stroke
				(width 0.1)
				(type default)
			)
			(layer "F.Fab")
		)
		(fp_line
			(start -0.12065 -0.2794)
			(end 0.12065 -0.2794)
			(stroke
				(width 0.1)
				(type default)
			)
			(layer "F.Fab")
		)
		(fp_line
			(start 0.12065 -0.2794)
			(end 0.12065 -0.3048)
			(stroke
				(width 0.1)
				(type default)
			)
			(layer "F.Fab")
		)
		(fp_line
			(start 0.12065 -0.3048)
			(end 0.67945 -0.3048)
			(stroke
				(width 0.1)
				(type default)
			)
			(layer "F.Fab")
		)
		(fp_line
			(start 0.67945 -0.3048)
			(end 0.67945 0.3048)
			(stroke
				(width 0.1)
				(type default)
			)
			(layer "F.Fab")
		)
		(fp_line
			(start -0.67945 -0.305054)
			(end -0.12065 -0.305054)
			(stroke
				(width 0.1)
				(type default)
			)
			(layer "F.Fab")
		)
		(fp_line
			(start -0.12065 -0.305054)
			(end -0.12065 -0.2794)
			(stroke
				(width 0.1)
				(type default)
			)
			(layer "F.Fab")
		)
		(pad "1" smd circle
			(at -0.40005 0 270)
			(size 0 0)
			(layers "F.Cu" "F.Mask" "F.Paste")
			(net "P0V9_RETIMER_CPU1_EN0_R")
		)
		(pad "2" smd circle
			(at 0.40005 0 270)
			(size 0 0)
			(layers "F.Cu" "F.Mask" "F.Paste")
			(net "GND")
		)
	)
	(footprint ""
		(layer "F.Cu")
		(at 398.276318 -75.518264)
		(property "Reference" "C1097"
			(at 0 0 0)
			(layer "F.SilkS")
			(hide yes)
			(effects
				(font
					(size 1.27 1.27)
				)
			)
		)
		(property "Value" ""
			(at 0 0 0)
			(layer "F.Fab")
			(effects
				(font
					(size 1.27 1.27)
				)
			)
		)
		(duplicate_pad_numbers_are_jumpers no)
		(fp_line
			(start -0.7874 -0.4064)
			(end 0.7874 -0.4064)
			(stroke
				(width 0.1524)
				(type default)
			)
			(layer "F.SilkS")
		)
		(fp_line
			(start -0.7874 0.4064)
			(end -0.7874 -0.4064)
			(stroke
				(width 0.1524)
				(type default)
			)
			(layer "F.SilkS")
		)
		(fp_line
			(start 0.7874 -0.4064)
			(end 0.7874 0.4064)
			(stroke
				(width 0.1524)
				(type default)
			)
			(layer "F.SilkS")
		)
		(fp_line
			(start 0.7874 0.4064)
			(end -0.7874 0.4064)
			(stroke
				(width 0.1524)
				(type default)
			)
			(layer "F.SilkS")
		)
		(fp_line
			(start -0.67945 -0.305054)
			(end -0.12065 -0.305054)
			(stroke
				(width 0.1)
				(type default)
			)
			(layer "F.Fab")
		)
		(fp_line
			(start -0.67945 0.3048)
			(end -0.67945 -0.305054)
			(stroke
				(width 0.1)
				(type default)
			)
			(layer "F.Fab")
		)
		(fp_line
			(start -0.12065 -0.305054)
			(end -0.12065 -0.2794)
			(stroke
				(width 0.1)
				(type default)
			)
			(layer "F.Fab")
		)
		(fp_line
			(start -0.12065 -0.2794)
			(end 0.12065 -0.2794)
			(stroke
				(width 0.1)
				(type default)
			)
			(layer "F.Fab")
		)
		(fp_line
			(start -0.12065 0.2794)
			(end -0.12065 0.3048)
			(stroke
				(width 0.1)
				(type default)
			)
			(layer "F.Fab")
		)
		(fp_line
			(start -0.12065 0.3048)
			(end -0.67945 0.3048)
			(stroke
				(width 0.1)
				(type default)
			)
			(layer "F.Fab")
		)
		(fp_line
			(start 0.120396 0.2794)
			(end -0.12065 0.2794)
			(stroke
				(width 0.1)
				(type default)
			)
			(layer "F.Fab")
		)
		(fp_line
			(start 0.120396 0.3048)
			(end 0.120396 0.2794)
			(stroke
				(width 0.1)
				(type default)
			)
			(layer "F.Fab")
		)
		(fp_line
			(start 0.12065 -0.3048)
			(end 0.67945 -0.3048)
			(stroke
				(width 0.1)
				(type default)
			)
			(layer "F.Fab")
		)
		(fp_line
			(start 0.12065 -0.2794)
			(end 0.12065 -0.3048)
			(stroke
				(width 0.1)
				(type default)
			)
			(layer "F.Fab")
		)
		(fp_line
			(start 0.67945 -0.3048)
			(end 0.67945 0.3048)
			(stroke
				(width 0.1)
				(type default)
			)
			(layer "F.Fab")
		)
		(fp_line
			(start 0.67945 0.3048)
			(end 0.120396 0.3048)
			(stroke
				(width 0.1)
				(type default)
			)
			(layer "F.Fab")
		)
		(pad "1" smd circle
			(at -0.40005 0)
			(size 0 0)
			(layers "F.Cu" "F.Mask" "F.Paste")
			(net "P3V3_AUX")
		)
		(pad "2" smd circle
			(at 0.40005 0)
			(size 0 0)
			(layers "F.Cu" "F.Mask" "F.Paste")
			(net "GND")
		)
	)
	(footprint ""
		(layer "F.Cu")
		(at 402.126958 -321.002152 90)
		(property "Reference" "R276"
			(at 0 0 90)
			(layer "F.SilkS")
			(hide yes)
			(effects
				(font
					(size 1.27 1.27)
				)
			)
		)
		(property "Value" ""
			(at 0 0 90)
			(layer "F.Fab")
			(effects
				(font
					(size 1.27 1.27)
				)
			)
		)
		(duplicate_pad_numbers_are_jumpers no)
		(fp_line
			(start 0.7874 -0.4064)
			(end 0.7874 0.4064)
			(stroke
				(width 0.1524)
				(type default)
			)
			(layer "F.SilkS")
		)
		(fp_line
			(start -0.7874 -0.4064)
			(end 0.7874 -0.4064)
			(stroke
				(width 0.1524)
				(type default)
			)
			(layer "F.SilkS")
		)
		(fp_line
			(start 0.7874 0.4064)
			(end -0.7874 0.4064)
			(stroke
				(width 0.1524)
				(type default)
			)
			(layer "F.SilkS")
		)
		(fp_line
			(start -0.7874 0.4064)
			(end -0.7874 -0.4064)
			(stroke
				(width 0.1524)
				(type default)
			)
			(layer "F.SilkS")
		)
		(fp_line
			(start -0.12065 -0.305054)
			(end -0.12065 -0.2794)
			(stroke
				(width 0.1)
				(type default)
			)
			(layer "F.Fab")
		)
		(fp_line
			(start -0.67945 -0.305054)
			(end -0.12065 -0.305054)
			(stroke
				(width 0.1)
				(type default)
			)
			(layer "F.Fab")
		)
		(fp_line
			(start 0.67945 -0.3048)
			(end 0.67945 0.3048)
			(stroke
				(width 0.1)
				(type default)
			)
			(layer "F.Fab")
		)
		(fp_line
			(start 0.12065 -0.3048)
			(end 0.67945 -0.3048)
			(stroke
				(width 0.1)
				(type default)
			)
			(layer "F.Fab")
		)
		(fp_line
			(start 0.12065 -0.2794)
			(end 0.12065 -0.3048)
			(stroke
				(width 0.1)
				(type default)
			)
			(layer "F.Fab")
		)
		(fp_line
			(start -0.12065 -0.2794)
			(end 0.12065 -0.2794)
			(stroke
				(width 0.1)
				(type default)
			)
			(layer "F.Fab")
		)
		(fp_line
			(start 0.120396 0.2794)
			(end -0.12065 0.2794)
			(stroke
				(width 0.1)
				(type default)
			)
			(layer "F.Fab")
		)
		(fp_line
			(start -0.12065 0.2794)
			(end -0.12065 0.3048)
			(stroke
				(width 0.1)
				(type default)
			)
			(layer "F.Fab")
		)
		(fp_line
			(start 0.67945 0.3048)
			(end 0.120396 0.3048)
			(stroke
				(width 0.1)
				(type default)
			)
			(layer "F.Fab")
		)
		(fp_line
			(start 0.120396 0.3048)
			(end 0.120396 0.2794)
			(stroke
				(width 0.1)
				(type default)
			)
			(layer "F.Fab")
		)
		(fp_line
			(start -0.12065 0.3048)
			(end -0.67945 0.3048)
			(stroke
				(width 0.1)
				(type default)
			)
			(layer "F.Fab")
		)
		(fp_line
			(start -0.67945 0.3048)
			(end -0.67945 -0.305054)
			(stroke
				(width 0.1)
				(type default)
			)
			(layer "F.Fab")
		)
		(pad "1" smd circle
			(at -0.40005 0 90)
			(size 0 0)
			(layers "F.Cu" "F.Mask" "F.Paste")
			(net "CPU0_PWR_GOOD")
		)
		(pad "2" smd circle
			(at 0.40005 0 90)
			(size 0 0)
			(layers "F.Cu" "F.Mask" "F.Paste")
			(net "PVDD18_S5_P0")
		)
	)
	(footprint ""
		(layer "F.Cu")
		(at 113.375948 -256.012442 90)
		(property "Reference" "C2439"
			(at 0 0 90)
			(layer "F.SilkS")
			(hide yes)
			(effects
				(font
					(size 1.27 1.27)
				)
			)
		)
		(property "Value" ""
			(at 0 0 90)
			(layer "F.Fab")
			(effects
				(font
					(size 1.27 1.27)
				)
			)
		)
		(duplicate_pad_numbers_are_jumpers no)
		(fp_line
			(start 0.7874 -0.4064)
			(end 0.7874 0.4064)
			(stroke
				(width 0.1524)
				(type default)
			)
			(layer "F.SilkS")
		)
		(fp_line
			(start -0.7874 -0.4064)
			(end 0.7874 -0.4064)
			(stroke
				(width 0.1524)
				(type default)
			)
			(layer "F.SilkS")
		)
		(fp_line
			(start 0.7874 0.4064)
			(end -0.7874 0.4064)
			(stroke
				(width 0.1524)
				(type default)
			)
			(layer "F.SilkS")
		)
		(fp_line
			(start -0.7874 0.4064)
			(end -0.7874 -0.4064)
			(stroke
				(width 0.1524)
				(type default)
			)
			(layer "F.SilkS")
		)
		(fp_line
			(start -0.12065 -0.305054)
			(end -0.12065 -0.2794)
			(stroke
				(width 0.1)
				(type default)
			)
			(layer "F.Fab")
		)
		(fp_line
			(start -0.67945 -0.305054)
			(end -0.12065 -0.305054)
			(stroke
				(width 0.1)
				(type default)
			)
			(layer "F.Fab")
		)
		(fp_line
			(start 0.67945 -0.3048)
			(end 0.67945 0.3048)
			(stroke
				(width 0.1)
				(type default)
			)
			(layer "F.Fab")
		)
		(fp_line
			(start 0.12065 -0.3048)
			(end 0.67945 -0.3048)
			(stroke
				(width 0.1)
				(type default)
			)
			(layer "F.Fab")
		)
		(fp_line
			(start 0.12065 -0.2794)
			(end 0.12065 -0.3048)
			(stroke
				(width 0.1)
				(type default)
			)
			(layer "F.Fab")
		)
		(fp_line
			(start -0.12065 -0.2794)
			(end 0.12065 -0.2794)
			(stroke
				(width 0.1)
				(type default)
			)
			(layer "F.Fab")
		)
		(fp_line
			(start 0.120396 0.2794)
			(end -0.12065 0.2794)
			(stroke
				(width 0.1)
				(type default)
			)
			(layer "F.Fab")
		)
		(fp_line
			(start -0.12065 0.2794)
			(end -0.12065 0.3048)
			(stroke
				(width 0.1)
				(type default)
			)
			(layer "F.Fab")
		)
		(fp_line
			(start 0.67945 0.3048)
			(end 0.120396 0.3048)
			(stroke
				(width 0.1)
				(type default)
			)
			(layer "F.Fab")
		)
		(fp_line
			(start 0.120396 0.3048)
			(end 0.120396 0.2794)
			(stroke
				(width 0.1)
				(type default)
			)
			(layer "F.Fab")
		)
		(fp_line
			(start -0.12065 0.3048)
			(end -0.67945 0.3048)
			(stroke
				(width 0.1)
				(type default)
			)
			(layer "F.Fab")
		)
		(fp_line
			(start -0.67945 0.3048)
			(end -0.67945 -0.305054)
			(stroke
				(width 0.1)
				(type default)
			)
			(layer "F.Fab")
		)
		(pad "1" smd circle
			(at -0.40005 0 90)
			(size 0 0)
			(layers "F.Cu" "F.Mask" "F.Paste")
			(net "PVDDCR_SOC_P1")
		)
		(pad "2" smd circle
			(at 0.40005 0 90)
			(size 0 0)
			(layers "F.Cu" "F.Mask" "F.Paste")
			(net "GND")
		)
	)
	(footprint ""
		(layer "F.Cu")
		(at 171.196 -110.200948 180)
		(property "Reference" "R6095"
			(at 0 0 180)
			(layer "F.SilkS")
			(hide yes)
			(effects
				(font
					(size 1.27 1.27)
				)
			)
		)
		(property "Value" ""
			(at 0 0 180)
			(layer "F.Fab")
			(effects
				(font
					(size 1.27 1.27)
				)
			)
		)
		(duplicate_pad_numbers_are_jumpers no)
		(fp_line
			(start 0.7874 0.4064)
			(end -0.7874 0.4064)
			(stroke
				(width 0.1524)
				(type default)
			)
			(layer "F.SilkS")
		)
		(fp_line
			(start 0.7874 -0.4064)
			(end 0.7874 0.4064)
			(stroke
				(width 0.1524)
				(type default)
			)
			(layer "F.SilkS")
		)
		(fp_line
			(start -0.7874 0.4064)
			(end -0.7874 -0.4064)
			(stroke
				(width 0.1524)
				(type default)
			)
			(layer "F.SilkS")
		)
		(fp_line
			(start -0.7874 -0.4064)
			(end 0.7874 -0.4064)
			(stroke
				(width 0.1524)
				(type default)
			)
			(layer "F.SilkS")
		)
		(fp_line
			(start 0.67945 0.3048)
			(end 0.120396 0.3048)
			(stroke
				(width 0.1)
				(type default)
			)
			(layer "F.Fab")
		)
		(fp_line
			(start 0.67945 -0.3048)
			(end 0.67945 0.3048)
			(stroke
				(width 0.1)
				(type default)
			)
			(layer "F.Fab")
		)
		(fp_line
			(start 0.12065 -0.2794)
			(end 0.12065 -0.3048)
			(stroke
				(width 0.1)
				(type default)
			)
			(layer "F.Fab")
		)
		(fp_line
			(start 0.12065 -0.3048)
			(end 0.67945 -0.3048)
			(stroke
				(width 0.1)
				(type default)
			)
			(layer "F.Fab")
		)
		(fp_line
			(start 0.120396 0.3048)
			(end 0.120396 0.2794)
			(stroke
				(width 0.1)
				(type default)
			)
			(layer "F.Fab")
		)
		(fp_line
			(start 0.120396 0.2794)
			(end -0.12065 0.2794)
			(stroke
				(width 0.1)
				(type default)
			)
			(layer "F.Fab")
		)
		(fp_line
			(start -0.12065 0.3048)
			(end -0.67945 0.3048)
			(stroke
				(width 0.1)
				(type default)
			)
			(layer "F.Fab")
		)
		(fp_line
			(start -0.12065 0.2794)
			(end -0.12065 0.3048)
			(stroke
				(width 0.1)
				(type default)
			)
			(layer "F.Fab")
		)
		(fp_line
			(start -0.12065 -0.2794)
			(end 0.12065 -0.2794)
			(stroke
				(width 0.1)
				(type default)
			)
			(layer "F.Fab")
		)
		(fp_line
			(start -0.12065 -0.305054)
			(end -0.12065 -0.2794)
			(stroke
				(width 0.1)
				(type default)
			)
			(layer "F.Fab")
		)
		(fp_line
			(start -0.67945 0.3048)
			(end -0.67945 -0.305054)
			(stroke
				(width 0.1)
				(type default)
			)
			(layer "F.Fab")
		)
		(fp_line
			(start -0.67945 -0.305054)
			(end -0.12065 -0.305054)
			(stroke
				(width 0.1)
				(type default)
			)
			(layer "F.Fab")
		)
		(pad "1" smd circle
			(at -0.40005 0 180)
			(size 0 0)
			(layers "F.Cu" "F.Mask" "F.Paste")
			(net "IRQ_HSC_FAULT_BUF_R_N")
		)
		(pad "2" smd circle
			(at 0.40005 0 180)
			(size 0 0)
			(layers "F.Cu" "F.Mask" "F.Paste")
			(net "IRQ_HSC_FAULT_BUF_N")
		)
	)
)
